(kicad_pcb
	(version 20260206)
	(generator "pcbnew")
	(generator_version "10.0")
	(general
		(thickness 1.6)
		(legacy_teardrops no)
	)
	(paper "A4")
	(title_block
		(title "12092022_DA0F0TMDCD0_F0T_Management_Board_D_brd_V3_OCP.brd")
		(comment 1 "Grand Teton / footprints 360-365 of 1440")
	)
	(layers
		(0 "F.Cu" signal "TOP")
		(4 "In1.Cu" signal "GND")
		(6 "In2.Cu" signal "IN1")
		(8 "In3.Cu" signal "GND1")
		(10 "In4.Cu" signal "IN2")
		(12 "In5.Cu" signal "VCC")
		(14 "In6.Cu" signal "VCC1")
		(16 "In7.Cu" signal "IN3")
		(18 "In8.Cu" signal "GND2")
		(20 "In9.Cu" signal "IN4")
		(22 "In10.Cu" signal "GND3")
		(2 "B.Cu" signal "BOTTOM")
		(9 "F.Adhes" user "F.Adhesive")
		(11 "B.Adhes" user "B.Adhesive")
		(13 "F.Paste" user "Package Geometry/Pastemask Top")
		(15 "B.Paste" user "Package Geometry/Pastemask Bottom")
		(5 "F.SilkS" user "Ref Des/Silkscreen Top")
		(7 "B.SilkS" user "Ref Des/Silkscreen Bottom")
		(1 "F.Mask" user "Board Geometry/Soldermask Top")
		(3 "B.Mask" user "Board Geometry/Soldermask Bottom")
		(17 "Dwgs.User" user "User.Drawings")
		(19 "Cmts.User" user "User.Comments")
		(21 "Eco1.User" user "User.Eco1")
		(23 "Eco2.User" user "User.Eco2")
		(25 "Edge.Cuts" user "Board Geometry/Outline")
		(27 "Margin" user)
		(31 "F.CrtYd" user "Package Geometry/Place Bound Top")
		(29 "B.CrtYd" user "Package Geometry/Place Bound Bottom")
		(35 "F.Fab" user "Ref Des/Assembly Top")
		(33 "B.Fab" user "Ref Des/Assembly Bottom")
	)
	(footprint ""
		(layer "F.Cu")
		(at 10.922 -106.6038)
		(property "Reference" "R125"
			(at 0 0 0)
			(layer "F.SilkS")
			(hide yes)
			(effects
				(font
					(size 1.27 1.27)
				)
			)
		)
		(property "Value" ""
			(at 0 0 0)
			(layer "F.Fab")
			(effects
				(font
					(size 1.27 1.27)
				)
			)
		)
		(duplicate_pad_numbers_are_jumpers no)
		(fp_line
			(start -0.7874 -0.4064)
			(end 0.7874 -0.4064)
			(stroke
				(width 0.1524)
				(type default)
			)
			(layer "F.SilkS")
		)
		(fp_line
			(start -0.7874 0.4064)
			(end -0.7874 -0.4064)
			(stroke
				(width 0.1524)
				(type default)
			)
			(layer "F.SilkS")
		)
		(fp_line
			(start 0.7874 -0.4064)
			(end 0.7874 0.4064)
			(stroke
				(width 0.1524)
				(type default)
			)
			(layer "F.SilkS")
		)
		(fp_line
			(start 0.7874 0.4064)
			(end -0.7874 0.4064)
			(stroke
				(width 0.1524)
				(type default)
			)
			(layer "F.SilkS")
		)
		(fp_line
			(start -0.67945 -0.305054)
			(end -0.12065 -0.305054)
			(stroke
				(width 0.1)
				(type default)
			)
			(layer "F.Fab")
		)
		(fp_line
			(start -0.67945 0.3048)
			(end -0.67945 -0.305054)
			(stroke
				(width 0.1)
				(type default)
			)
			(layer "F.Fab")
		)
		(fp_line
			(start -0.12065 -0.305054)
			(end -0.12065 -0.2794)
			(stroke
				(width 0.1)
				(type default)
			)
			(layer "F.Fab")
		)
		(fp_line
			(start -0.12065 -0.2794)
			(end 0.12065 -0.2794)
			(stroke
				(width 0.1)
				(type default)
			)
			(layer "F.Fab")
		)
		(fp_line
			(start -0.12065 0.2794)
			(end -0.12065 0.3048)
			(stroke
				(width 0.1)
				(type default)
			)
			(layer "F.Fab")
		)
		(fp_line
			(start -0.12065 0.3048)
			(end -0.67945 0.3048)
			(stroke
				(width 0.1)
				(type default)
			)
			(layer "F.Fab")
		)
		(fp_line
			(start 0.120396 0.2794)
			(end -0.12065 0.2794)
			(stroke
				(width 0.1)
				(type default)
			)
			(layer "F.Fab")
		)
		(fp_line
			(start 0.120396 0.3048)
			(end 0.120396 0.2794)
			(stroke
				(width 0.1)
				(type default)
			)
			(layer "F.Fab")
		)
		(fp_line
			(start 0.12065 -0.3048)
			(end 0.67945 -0.3048)
			(stroke
				(width 0.1)
				(type default)
			)
			(layer "F.Fab")
		)
		(fp_line
			(start 0.12065 -0.2794)
			(end 0.12065 -0.3048)
			(stroke
				(width 0.1)
				(type default)
			)
			(layer "F.Fab")
		)
		(fp_line
			(start 0.67945 -0.3048)
			(end 0.67945 0.3048)
			(stroke
				(width 0.1)
				(type default)
			)
			(layer "F.Fab")
		)
		(fp_line
			(start 0.67945 0.3048)
			(end 0.120396 0.3048)
			(stroke
				(width 0.1)
				(type default)
			)
			(layer "F.Fab")
		)
		(pad "1" smd circle
			(at -0.40005 0)
			(size 0 0)
			(layers "F.Cu" "F.Mask" "F.Paste")
			(net "RST_BMC_SRST_BUF_R_N")
		)
		(pad "2" smd circle
			(at 0.40005 0)
			(size 0 0)
			(layers "F.Cu" "F.Mask" "F.Paste")
			(net "RST_BMC_SRST_N")
		)
	)
	(footprint ""
		(layer "F.Cu")
		(at 15.5448 -70.7136 -90)
		(property "Reference" "R664"
			(at 0 0 270)
			(layer "F.SilkS")
			(hide yes)
			(effects
				(font
					(size 1.27 1.27)
				)
			)
		)
		(property "Value" ""
			(at 0 0 270)
			(layer "F.Fab")
			(effects
				(font
					(size 1.27 1.27)
				)
			)
		)
		(duplicate_pad_numbers_are_jumpers no)
		(fp_line
			(start -0.7874 0.4064)
			(end -0.7874 -0.4064)
			(stroke
				(width 0.1524)
				(type default)
			)
			(layer "F.SilkS")
		)
		(fp_line
			(start 0.7874 0.4064)
			(end -0.7874 0.4064)
			(stroke
				(width 0.1524)
				(type default)
			)
			(layer "F.SilkS")
		)
		(fp_line
			(start -0.7874 -0.4064)
			(end 0.7874 -0.4064)
			(stroke
				(width 0.1524)
				(type default)
			)
			(layer "F.SilkS")
		)
		(fp_line
			(start 0.7874 -0.4064)
			(end 0.7874 0.4064)
			(stroke
				(width 0.1524)
				(type default)
			)
			(layer "F.SilkS")
		)
		(fp_line
			(start -0.67945 0.3048)
			(end -0.67945 -0.305054)
			(stroke
				(width 0.1)
				(type default)
			)
			(layer "F.Fab")
		)
		(fp_line
			(start -0.12065 0.3048)
			(end -0.67945 0.3048)
			(stroke
				(width 0.1)
				(type default)
			)
			(layer "F.Fab")
		)
		(fp_line
			(start 0.120396 0.3048)
			(end 0.120396 0.2794)
			(stroke
				(width 0.1)
				(type default)
			)
			(layer "F.Fab")
		)
		(fp_line
			(start 0.67945 0.3048)
			(end 0.120396 0.3048)
			(stroke
				(width 0.1)
				(type default)
			)
			(layer "F.Fab")
		)
		(fp_line
			(start -0.12065 0.2794)
			(end -0.12065 0.3048)
			(stroke
				(width 0.1)
				(type default)
			)
			(layer "F.Fab")
		)
		(fp_line
			(start 0.120396 0.2794)
			(end -0.12065 0.2794)
			(stroke
				(width 0.1)
				(type default)
			)
			(layer "F.Fab")
		)
		(fp_line
			(start -0.12065 -0.2794)
			(end 0.12065 -0.2794)
			(stroke
				(width 0.1)
				(type default)
			)
			(layer "F.Fab")
		)
		(fp_line
			(start 0.12065 -0.2794)
			(end 0.12065 -0.3048)
			(stroke
				(width 0.1)
				(type default)
			)
			(layer "F.Fab")
		)
		(fp_line
			(start 0.12065 -0.3048)
			(end 0.67945 -0.3048)
			(stroke
				(width 0.1)
				(type default)
			)
			(layer "F.Fab")
		)
		(fp_line
			(start 0.67945 -0.3048)
			(end 0.67945 0.3048)
			(stroke
				(width 0.1)
				(type default)
			)
			(layer "F.Fab")
		)
		(fp_line
			(start -0.67945 -0.305054)
			(end -0.12065 -0.305054)
			(stroke
				(width 0.1)
				(type default)
			)
			(layer "F.Fab")
		)
		(fp_line
			(start -0.12065 -0.305054)
			(end -0.12065 -0.2794)
			(stroke
				(width 0.1)
				(type default)
			)
			(layer "F.Fab")
		)
		(pad "1" smd circle
			(at -0.40005 0 270)
			(size 0 0)
			(layers "F.Cu" "F.Mask" "F.Paste")
			(net "SPI_BMC_BT_WP1_N_R")
		)
		(pad "2" smd circle
			(at 0.40005 0 270)
			(size 0 0)
			(layers "F.Cu" "F.Mask" "F.Paste")
			(net "GND")
		)
	)
	(footprint ""
		(layer "F.Cu")
		(at 33.2994 -61.976)
		(property "Reference" "U49"
			(at -2.794 3.55727 0)
			(unlocked yes)
			(layer "F.SilkS")
			(effects
				(font
					(size 0.7874 0.5842)
					(thickness 0.1524)
				)
			)
		)
		(property "Value" ""
			(at 0 0 0)
			(layer "F.Fab")
			(effects
				(font
					(size 1.27 1.27)
				)
			)
		)
		(duplicate_pad_numbers_are_jumpers no)
		(fp_line
			(start -1.834896 -1.575054)
			(end -0.508 -1.575054)
			(stroke
				(width 0.1524)
				(type default)
			)
			(layer "F.SilkS")
		)
		(fp_line
			(start -1.834896 1.575054)
			(end -1.834896 -1.575054)
			(stroke
				(width 0.1524)
				(type default)
			)
			(layer "F.SilkS")
		)
		(fp_line
			(start -0.508 -1.575054)
			(end 0 -1.016)
			(stroke
				(width 0.1524)
				(type default)
			)
			(layer "F.SilkS")
		)
		(fp_line
			(start 0 -1.016)
			(end 0.508 -1.575054)
			(stroke
				(width 0.1524)
				(type default)
			)
			(layer "F.SilkS")
		)
		(fp_line
			(start 0.508 -1.575054)
			(end 1.834896 -1.575054)
			(stroke
				(width 0.1524)
				(type default)
			)
			(layer "F.SilkS")
		)
		(fp_line
			(start 1.834896 -1.575054)
			(end 1.834896 1.575054)
			(stroke
				(width 0.1524)
				(type default)
			)
			(layer "F.SilkS")
		)
		(fp_line
			(start 1.834896 1.575054)
			(end -1.834896 1.575054)
			(stroke
				(width 0.1524)
				(type default)
			)
			(layer "F.SilkS")
		)
		(fp_poly
			(pts
				(xy -3.028696 -1.73736) (xy -3.028696 -0.72136) (xy -2.012696 -1.22936)
			)
			(stroke
				(width 0)
				(type default)
			)
			(fill yes)
			(layer "F.SilkS")
		)
		(fp_line
			(start -0.824992 -1.575054)
			(end 0.824992 -1.575054)
			(stroke
				(width 0.1)
				(type default)
			)
			(layer "F.Fab")
		)
		(fp_line
			(start -0.824992 1.575054)
			(end -0.824992 -1.575054)
			(stroke
				(width 0.1)
				(type default)
			)
			(layer "F.Fab")
		)
		(fp_line
			(start 0.824992 -1.575054)
			(end 0.824992 1.575054)
			(stroke
				(width 0.1)
				(type default)
			)
			(layer "F.Fab")
		)
		(fp_line
			(start 0.824992 1.575054)
			(end -0.824992 1.575054)
			(stroke
				(width 0.1)
				(type default)
			)
			(layer "F.Fab")
		)
		(fp_poly
			(pts
				(xy -3.003296 -1.45796) (xy -3.003296 -0.44196) (xy -1.987296 -0.94996)
			)
			(stroke
				(width 0)
				(type default)
			)
			(fill yes)
			(layer "F.Fab")
		)
		(pad "1" smd rect
			(at -1.199896 -0.94996 270)
			(size 0.7112 1.016)
			(layers "F.Cu" "F.Mask" "F.Paste")
			(net "PWRGD_P5V_AUX")
		)
		(pad "2" smd rect
			(at -1.199896 0 270)
			(size 0.7112 1.016)
			(layers "F.Cu" "F.Mask" "F.Paste")
			(net "PWRGD_P3V3_RGM_R2")
		)
		(pad "3" smd rect
			(at -1.199896 0.94996 270)
			(size 0.7112 1.016)
			(layers "F.Cu" "F.Mask" "F.Paste")
			(net "GND")
		)
		(pad "4" smd rect
			(at 1.199896 0.94996 270)
			(size 0.7112 1.016)
			(layers "F.Cu" "F.Mask" "F.Paste")
			(net "EN_P1V8")
		)
		(pad "5" smd rect
			(at 1.199896 -0.94996 270)
			(size 0.7112 1.016)
			(layers "F.Cu" "F.Mask" "F.Paste")
			(net "P3V3_LDO")
		)
	)
	(footprint ""
		(layer "F.Cu")
		(at 71.4502 -27.9146 -90)
		(property "Reference" "R872"
			(at 0 0 270)
			(layer "F.SilkS")
			(hide yes)
			(effects
				(font
					(size 1.27 1.27)
				)
			)
		)
		(property "Value" ""
			(at 0 0 270)
			(layer "F.Fab")
			(effects
				(font
					(size 1.27 1.27)
				)
			)
		)
		(duplicate_pad_numbers_are_jumpers no)
		(fp_line
			(start -0.7874 0.4064)
			(end -0.7874 -0.4064)
			(stroke
				(width 0.1524)
				(type default)
			)
			(layer "F.SilkS")
		)
		(fp_line
			(start 0.7874 0.4064)
			(end -0.7874 0.4064)
			(stroke
				(width 0.1524)
				(type default)
			)
			(layer "F.SilkS")
		)
		(fp_line
			(start -0.7874 -0.4064)
			(end 0.7874 -0.4064)
			(stroke
				(width 0.1524)
				(type default)
			)
			(layer "F.SilkS")
		)
		(fp_line
			(start 0.7874 -0.4064)
			(end 0.7874 0.4064)
			(stroke
				(width 0.1524)
				(type default)
			)
			(layer "F.SilkS")
		)
		(fp_line
			(start -0.67945 0.3048)
			(end -0.67945 -0.305054)
			(stroke
				(width 0.1)
				(type default)
			)
			(layer "F.Fab")
		)
		(fp_line
			(start -0.12065 0.3048)
			(end -0.67945 0.3048)
			(stroke
				(width 0.1)
				(type default)
			)
			(layer "F.Fab")
		)
		(fp_line
			(start 0.120396 0.3048)
			(end 0.120396 0.2794)
			(stroke
				(width 0.1)
				(type default)
			)
			(layer "F.Fab")
		)
		(fp_line
			(start 0.67945 0.3048)
			(end 0.120396 0.3048)
			(stroke
				(width 0.1)
				(type default)
			)
			(layer "F.Fab")
		)
		(fp_line
			(start -0.12065 0.2794)
			(end -0.12065 0.3048)
			(stroke
				(width 0.1)
				(type default)
			)
			(layer "F.Fab")
		)
		(fp_line
			(start 0.120396 0.2794)
			(end -0.12065 0.2794)
			(stroke
				(width 0.1)
				(type default)
			)
			(layer "F.Fab")
		)
		(fp_line
			(start -0.12065 -0.2794)
			(end 0.12065 -0.2794)
			(stroke
				(width 0.1)
				(type default)
			)
			(layer "F.Fab")
		)
		(fp_line
			(start 0.12065 -0.2794)
			(end 0.12065 -0.3048)
			(stroke
				(width 0.1)
				(type default)
			)
			(layer "F.Fab")
		)
		(fp_line
			(start 0.12065 -0.3048)
			(end 0.67945 -0.3048)
			(stroke
				(width 0.1)
				(type default)
			)
			(layer "F.Fab")
		)
		(fp_line
			(start 0.67945 -0.3048)
			(end 0.67945 0.3048)
			(stroke
				(width 0.1)
				(type default)
			)
			(layer "F.Fab")
		)
		(fp_line
			(start -0.67945 -0.305054)
			(end -0.12065 -0.305054)
			(stroke
				(width 0.1)
				(type default)
			)
			(layer "F.Fab")
		)
		(fp_line
			(start -0.12065 -0.305054)
			(end -0.12065 -0.2794)
			(stroke
				(width 0.1)
				(type default)
			)
			(layer "F.Fab")
		)
		(pad "1" smd circle
			(at -0.40005 0 270)
			(size 0 0)
			(layers "F.Cu" "F.Mask" "F.Paste")
			(net "PWRGD_P3V3_RGM_R")
		)
		(pad "2" smd circle
			(at 0.40005 0 270)
			(size 0 0)
			(layers "F.Cu" "F.Mask" "F.Paste")
			(net "PWRGD_P3V3_RGM_R3")
		)
	)
	(footprint ""
		(layer "F.Cu")
		(at 40.756078 -36.578286 90)
		(property "Reference" "R156"
			(at 0 0 90)
			(layer "F.SilkS")
			(hide yes)
			(effects
				(font
					(size 1.27 1.27)
				)
			)
		)
		(property "Value" ""
			(at 0 0 90)
			(layer "F.Fab")
			(effects
				(font
					(size 1.27 1.27)
				)
			)
		)
		(duplicate_pad_numbers_are_jumpers no)
		(fp_line
			(start 0.7874 -0.4064)
			(end 0.7874 0.4064)
			(stroke
				(width 0.1524)
				(type default)
			)
			(layer "F.SilkS")
		)
		(fp_line
			(start -0.7874 -0.4064)
			(end 0.7874 -0.4064)
			(stroke
				(width 0.1524)
				(type default)
			)
			(layer "F.SilkS")
		)
		(fp_line
			(start 0.7874 0.4064)
			(end -0.7874 0.4064)
			(stroke
				(width 0.1524)
				(type default)
			)
			(layer "F.SilkS")
		)
		(fp_line
			(start -0.7874 0.4064)
			(end -0.7874 -0.4064)
			(stroke
				(width 0.1524)
				(type default)
			)
			(layer "F.SilkS")
		)
		(fp_line
			(start -0.12065 -0.305054)
			(end -0.12065 -0.2794)
			(stroke
				(width 0.1)
				(type default)
			)
			(layer "F.Fab")
		)
		(fp_line
			(start -0.67945 -0.305054)
			(end -0.12065 -0.305054)
			(stroke
				(width 0.1)
				(type default)
			)
			(layer "F.Fab")
		)
		(fp_line
			(start 0.67945 -0.3048)
			(end 0.67945 0.3048)
			(stroke
				(width 0.1)
				(type default)
			)
			(layer "F.Fab")
		)
		(fp_line
			(start 0.12065 -0.3048)
			(end 0.67945 -0.3048)
			(stroke
				(width 0.1)
				(type default)
			)
			(layer "F.Fab")
		)
		(fp_line
			(start 0.12065 -0.2794)
			(end 0.12065 -0.3048)
			(stroke
				(width 0.1)
				(type default)
			)
			(layer "F.Fab")
		)
		(fp_line
			(start -0.12065 -0.2794)
			(end 0.12065 -0.2794)
			(stroke
				(width 0.1)
				(type default)
			)
			(layer "F.Fab")
		)
		(fp_line
			(start 0.120396 0.2794)
			(end -0.12065 0.2794)
			(stroke
				(width 0.1)
				(type default)
			)
			(layer "F.Fab")
		)
		(fp_line
			(start -0.12065 0.2794)
			(end -0.12065 0.3048)
			(stroke
				(width 0.1)
				(type default)
			)
			(layer "F.Fab")
		)
		(fp_line
			(start 0.67945 0.3048)
			(end 0.120396 0.3048)
			(stroke
				(width 0.1)
				(type default)
			)
			(layer "F.Fab")
		)
		(fp_line
			(start 0.120396 0.3048)
			(end 0.120396 0.2794)
			(stroke
				(width 0.1)
				(type default)
			)
			(layer "F.Fab")
		)
		(fp_line
			(start -0.12065 0.3048)
			(end -0.67945 0.3048)
			(stroke
				(width 0.1)
				(type default)
			)
			(layer "F.Fab")
		)
		(fp_line
			(start -0.67945 0.3048)
			(end -0.67945 -0.305054)
			(stroke
				(width 0.1)
				(type default)
			)
			(layer "F.Fab")
		)
		(pad "1" smd circle
			(at -0.40005 0 90)
			(size 0 0)
			(layers "F.Cu" "F.Mask" "F.Paste")
			(net "P2V5_AUX")
		)
		(pad "2" smd circle
			(at 0.40005 0 90)
			(size 0 0)
			(layers "F.Cu" "F.Mask" "F.Paste")
			(net "P3V3_P2V5_P1V8_RVDD")
		)
	)
	(footprint ""
		(layer "F.Cu")
		(at 33.528 -64.4398 180)
		(property "Reference" "C298"
			(at 0 0 180)
			(layer "F.SilkS")
			(hide yes)
			(effects
				(font
					(size 1.27 1.27)
				)
			)
		)
		(property "Value" ""
			(at 0 0 180)
			(layer "F.Fab")
			(effects
				(font
					(size 1.27 1.27)
				)
			)
		)
		(duplicate_pad_numbers_are_jumpers no)
		(fp_line
			(start 0.7874 0.4064)
			(end -0.7874 0.4064)
			(stroke
				(width 0.1524)
				(type default)
			)
			(layer "F.SilkS")
		)
		(fp_line
			(start 0.7874 -0.4064)
			(end 0.7874 0.4064)
			(stroke
				(width 0.1524)
				(type default)
			)
			(layer "F.SilkS")
		)
		(fp_line
			(start -0.7874 0.4064)
			(end -0.7874 -0.4064)
			(stroke
				(width 0.1524)
				(type default)
			)
			(layer "F.SilkS")
		)
		(fp_line
			(start -0.7874 -0.4064)
			(end 0.7874 -0.4064)
			(stroke
				(width 0.1524)
				(type default)
			)
			(layer "F.SilkS")
		)
		(fp_line
			(start 0.67945 0.3048)
			(end 0.120396 0.3048)
			(stroke
				(width 0.1)
				(type default)
			)
			(layer "F.Fab")
		)
		(fp_line
			(start 0.67945 -0.3048)
			(end 0.67945 0.3048)
			(stroke
				(width 0.1)
				(type default)
			)
			(layer "F.Fab")
		)
		(fp_line
			(start 0.12065 -0.2794)
			(end 0.12065 -0.3048)
			(stroke
				(width 0.1)
				(type default)
			)
			(layer "F.Fab")
		)
		(fp_line
			(start 0.12065 -0.3048)
			(end 0.67945 -0.3048)
			(stroke
				(width 0.1)
				(type default)
			)
			(layer "F.Fab")
		)
		(fp_line
			(start 0.120396 0.3048)
			(end 0.120396 0.2794)
			(stroke
				(width 0.1)
				(type default)
			)
			(layer "F.Fab")
		)
		(fp_line
			(start 0.120396 0.2794)
			(end -0.12065 0.2794)
			(stroke
				(width 0.1)
				(type default)
			)
			(layer "F.Fab")
		)
		(fp_line
			(start -0.12065 0.3048)
			(end -0.67945 0.3048)
			(stroke
				(width 0.1)
				(type default)
			)
			(layer "F.Fab")
		)
		(fp_line
			(start -0.12065 0.2794)
			(end -0.12065 0.3048)
			(stroke
				(width 0.1)
				(type default)
			)
			(layer "F.Fab")
		)
		(fp_line
			(start -0.12065 -0.2794)
			(end 0.12065 -0.2794)
			(stroke
				(width 0.1)
				(type default)
			)
			(layer "F.Fab")
		)
		(fp_line
			(start -0.12065 -0.305054)
			(end -0.12065 -0.2794)
			(stroke
				(width 0.1)
				(type default)
			)
			(layer "F.Fab")
		)
		(fp_line
			(start -0.67945 0.3048)
			(end -0.67945 -0.305054)
			(stroke
				(width 0.1)
				(type default)
			)
			(layer "F.Fab")
		)
		(fp_line
			(start -0.67945 -0.305054)
			(end -0.12065 -0.305054)
			(stroke
				(width 0.1)
				(type default)
			)
			(layer "F.Fab")
		)
		(pad "1" smd circle
			(at -0.40005 0 180)
			(size 0 0)
			(layers "F.Cu" "F.Mask" "F.Paste")
			(net "P3V3_LDO")
		)
		(pad "2" smd circle
			(at 0.40005 0 180)
			(size 0 0)
			(layers "F.Cu" "F.Mask" "F.Paste")
			(net "GND")
		)
	)
)
